# BASEBOARD_FAB2 (Tioga Pass) — schematic parts with pin connectivity, parts 1996–2145 of 4751; source: Cadence DE-HDL packaged netlist (pstxprt.dat, pstxnet.dat, pstchip.dat)

C22W34  SC22U16V5MX-4-GP  20%  pkg SMD-BCG5  page 139 : 1 = P3V3_STBY ; 2 = GND
C22W35  SC22U16V5MX-4-GP  20%  pkg SMD-BCG5  page 139 : 1 = P1V5_LAN ; 2 = GND
C25P80  CAP_A  0.1UF 16V 10% X7R  pkg 0402V  page 252 : 1 = P5V_VGA_D ; 2 = GND
C25P83  CAP_A  0.1UF 16V 10% X7R  pkg 0402V  page 252 : 1 = P5V_VGA ; 2 = GND
C25W1  CAP  1.0UF 16V 10% X6S  pkg 0402  page 151 : 1 = P1V2_AUX_BMC ; 2 = GND
C25W2  CAP  1.0UF 16V 10% X6S  pkg 0402  page 151 : 1 = P1V2_AUX_BMC ; 2 = GND
C25W3  CAP  1.0UF 16V 10% X6S  pkg 0402  page 151 : 1 = P1V2_AUX_BMC ; 2 = GND
C25W4  CAP  1.0UF 16V 10% X6S  pkg 0402  page 151 : 1 = P1V2_AUX_BMC ; 2 = GND
C25W5  CAP  1.0UF 16V 10% X6S  pkg 0402  page 151 : 1 = P1V2_AUX_BMC ; 2 = GND
C25W6  CAP  1.0UF 16V 10% X6S  pkg 0402  page 151 : 1 = P1V2_AUX_BMC ; 2 = GND
C25W7  CAP_A  0.1UF 16V 10% X7R  pkg 0402V  page 147 : 1 = P3V3_STBY_BMC_ADCVREFP ; 2 = VCC_ADCAV3V3
C25W8  CAP_A  0.1UF 16V 10% X7R  pkg 0402V  page 147 : 1 = P3V3_STBY_BMC_ADCVREFN ; 2 = GND
C25W9  CAP_A  0.1UF 16V 10% X7R  pkg 0402V  page 147 : 1 = P3V3_STBY_BMC_ADCVREFP ; 2 = P3V3_STBY_BMC_ADCVREFN
C25W10  CAP_A  0.01UF 25V 10% X7R  pkg 0402V  page 151 : 1 = P1V2_AUX_BMC ; 2 = BMC_M_VREFCA
C25W11  CAP_A  0.01UF 25V 10% X7R  pkg 0402V  page 151 : 1 = BMC_M_VREFCA ; 2 = GND
C25W12  CAP_A  1.0UF 6.3V 10% X6S  pkg 0402V  page 151 : 1 = BMC_M_VREFCA ; 2 = GND
C25W13  CAP_A  0.1UF 16V 10% X7R  pkg 0402V  page 151 : 1 = BMC_M_VREFCA ; 2 = GND
C25W14  CAP_A  0.1UF 16V 10% X7R  pkg 0402V  page 151 : 1 = P2V5_AUX_BMC ; 2 = GND
C25W15  CAP_A  0.1UF 16V 10% X7R  pkg 0402V  page 151 : 1 = P2V5_AUX_BMC ; 2 = GND
C25W16  CAP  100.0PF 50V 5% COG  pkg 0402LF  page 151 : 1 = P1V2_AUX_BMC ; 2 = GND
C25W17  SC1U16V3KX-2GP  10%  pkg SMD-BCG  page 151 : 1 = P1V2_AUX_BMC ; 2 = GND
C25W18  SC1U16V3KX-2GP  10%  pkg SMD-BCG  page 151 : 1 = P1V2_AUX_BMC ; 2 = GND
C25W19  CAP  4.7UF 6.3V 10% X6S  pkg 0603  page 151 : 1 = P1V2_AUX_BMC ; 2 = GND
C25W20  CAP_A  0.1UF 16V 10% X7R  pkg 0402V  page 145 : 1 = P2E_SSB_BMC_RX_DP ; 2 = P2E_SSB_BMC_RX_C_DP
C25W21  CAP_A  0.1UF 16V 10% X7R  pkg 0402V  page 145 : 1 = P2E_SSB_BMC_RX_DN ; 2 = P2E_SSB_BMC_RX_C_DN
C25W22  CAP_A  0.1UF 16V 10% X7R  pkg 0402V  page 143 : 1 = BMC_M_VREFCA ; 2 = GND
C25W23  CAP  1.0UF 16V 10% X6S  pkg 0402  page 149 : 1 = P1V15_AUX_BMC ; 2 = GND
C25W24  CAP  1.0UF 16V 10% X6S  pkg 0402  page 149 : 1 = P1V15_AUX_BMC ; 2 = GND
C25W25  CAP  1.0UF 16V 10% X6S  pkg 0402  page 149 : 1 = P1V15_AUX_BMC ; 2 = GND
C25W26  CAP  1.0UF 16V 10% X6S  pkg 0402  page 149 : 1 = P1V15_AUX_BMC ; 2 = GND
C25W27  CAP  1.0UF 16V 10% X6S  pkg 0402  page 149 : 1 = P1V15_AUX_BMC ; 2 = GND
C25W28  CAP  1.0UF 16V 10% X6S  pkg 0402  page 149 : 1 = P1V15_AUX_BMC ; 2 = GND
C25W29  CAP  10UF 4V 20% X6S  pkg 0603LF  page 149 : 1 = P1V15_AUX_BMC ; 2 = GND
C25W30  CAP  4.7UF 6.3V 10% X6S  pkg 0603  page 149 : 1 = P1V15_AUX_BMC ; 2 = GND
C25W31  CAP_A  0.1UF 16V 10% X7R  pkg 0402V  page 149 : 1 = VCC_ADCAV3V3 ; 2 = GND
C25W32  CAP  1.0UF 16V 10% X6S  pkg 0402  page 149 : 1 = VCC_ADCAV3V3 ; 2 = GND
C25W33  CAP  1.0UF 16V 10% X6S  pkg 0402  page 149 : 1 = VCC_ADCAV3V3 ; 2 = GND
C25W34  CAP_A  0.1UF 16V 10% X7R  pkg 0402V  page 149 : 1 = VCC_DACAV3V3 ; 2 = GND
C25W35  CAP  1.0UF 16V 10% X6S  pkg 0402  page 149 : 1 = VCC_DACAV3V3 ; 2 = GND
C25W36  CAP  4.7UF 6.3V 10% X6S  pkg 0603  page 149 : 1 = VCC_DACAV3V3 ; 2 = GND
C25W37  CAP  1.0UF 16V 10% X6S  pkg 0402  page 149 : 1 = VCC_A_1V1 ; 2 = GND
C25W38  CAP_A  0.1UF 16V 10% X7R  pkg 0402V  page 149 : 1 = VCC_A_1V1 ; 2 = GND
C25W39  CAP  4.7UF 6.3V 10% X6S  pkg 0603  page 149 : 1 = VCC_A_1V1 ; 2 = GND
C25W40  CAP  1.0UF 16V 10% X6S  pkg 0402  page 149 : 1 = VCC_D_3V3 ; 2 = GND
C25W41  CAP  1.0UF 16V 10% X6S  pkg 0402  page 149 : 1 = VCC_D_3V3 ; 2 = GND
C25W42  CAP  1.0UF 16V 10% X6S  pkg 0402  page 149 : 1 = VCC_D_3V3 ; 2 = GND
C25W43  CAP  1.0UF 16V 10% X6S  pkg 0402  page 149 : 1 = VCC_D_3V3 ; 2 = GND
C25W44  CAP  1.0UF 16V 10% X6S  pkg 0402  page 149 : 1 = VCC_D_3V3 ; 2 = GND
C25W45  CAP_A  0.1UF 16V 10% X7R  pkg 0402V  page 149 : 1 = VCC_D_3V3 ; 2 = GND
C25W46  CAP  10UF 16V 10% X6S  pkg 0805  page 149 : 1 = VCC_D_3V3 ; 2 = GND
C25W47  CAP  4.7UF 6.3V 10% X6S  pkg 0603  page 149 : 1 = VCC_D_3V3 ; 2 = GND
C25W48  CAP  1.0UF 16V 10% X6S  pkg 0402  page 149 : 1 = P3V3_STBY ; 2 = GND
C25W49  CAP_A  0.1UF 16V 10% X7R  pkg 0402V  page 149 : 1 = P3V3_STBY ; 2 = GND
C25W50  CAP  4.7UF 6.3V 10% X6S  pkg 0603  page 149 : 1 = P3V3_STBY ; 2 = GND
C25W51  CAP  1.0UF 16V 10% X6S  pkg 0402  page 149 : 1 = P1V2_AUX_BMC ; 2 = GND
C25W52  CAP  1.0UF 16V 10% X6S  pkg 0402  page 149 : 1 = P1V2_AUX_BMC ; 2 = GND
C25W53  CAP  1.0UF 16V 10% X6S  pkg 0402  page 149 : 1 = P1V2_AUX_BMC ; 2 = GND
C25W54  CAP  1.0UF 16V 10% X6S  pkg 0402  page 149 : 1 = P1V2_AUX_BMC ; 2 = GND
C25W55  CAP_A  0.1UF 16V 10% X7R  pkg 0402V  page 149 : 1 = P1V2_AUX_BMC ; 2 = GND
C25W56  CAP  1.0UF 16V 10% X6S  pkg 0402  page 149 : 1 = VCC_PA_3V3 ; 2 = GND
C25W57  CAP  100.0PF 50V 5% COG  pkg 0402LF  page 149 : 1 = VCC_PA_3V3 ; 2 = GND
C25W58  CAP_A  0.1UF 16V 10% X7R  pkg 0402V  page 149 : 1 = VCC_PA_3V3 ; 2 = GND
C25W59  CAP  4.7UF 6.3V 10% X6S  pkg 0603  page 149 : 1 = VCC_PA_3V3 ; 2 = GND
C25W60  CAP  1.0UF 16V 10% X6S  pkg 0402  page 149 : 1 = P3V3_STBY ; 2 = GND
C25W61  CAP_A  0.1UF 16V 10% X7R  pkg 0402V  page 149 : 1 = P3V3_STBY ; 2 = GND
C25W62  CAP  4.7UF 6.3V 10% X6S  pkg 0603  page 149 : 1 = P3V3_STBY ; 2 = GND
C25W66  CAP  1.0UF 16V 10% X6S  pkg 0402  page 149 : 1 = VCC_VA_3V3 ; 2 = GND
C25W67  CAP  1.0UF 16V 10% X6S  pkg 0402  page 149 : 1 = VCC_VA_3V3 ; 2 = GND
C25W68  CAP_A  0.1UF 16V 10% X7R  pkg 0402V  page 149 : 1 = VCC_VA_3V3 ; 2 = GND
C25W69  CAP  4.7UF 6.3V 10% X6S  pkg 0603  page 149 : 1 = VCC_VA_3V3 ; 2 = GND
C25W70  CAP  4.7UF 6.3V 10% X6S  pkg 0603  page 149 : 1 = P3V3_USB2A_ALG ; 2 = GND
C25W71  CAP  1.0UF 16V 10% X6S  pkg 0402  page 149 : 1 = P3V3_USB2A_ALG ; 2 = GND
C25W72  CAP  12.0PF 50V 5% COG  pkg 0402LF  page 252 : 1 = BMC_VGA_BLUE ; 2 = GND
C25W73  CAP  12.0PF 50V 5% COG  pkg 0402LF  page 252 : 1 = BMC_VGA_GREEN ; 2 = GND
C25W74  CAP  12.0PF 50V 5% COG  pkg 0402LF  page 252 : 1 = BMC_VGA_RED ; 2 = GND
C25W75  CAP  12.0PF 50V 5% COG  pkg 0402LF  page 252 : 1 = V_IO_B_J ; 2 = GND
C25W76  CAP  12.0PF 50V 5% COG  pkg 0402LF  page 252 : 1 = V_IO_G_J ; 2 = GND
C25W77  CAP  12.0PF 50V 5% COG  pkg 0402LF  page 252 : 1 = V_IO_R_J ; 2 = GND
C25W78  CAP  100.0PF 50V 5% COG  pkg 0402LF  page 252 : 1 = V_IBMC_5V_DDC_SCL_J ; 2 = GND
C25W79  CAP  100.0PF 50V 5% COG  pkg 0402LF  page 252 : 1 = V_IBMC_5V_DDC_SDA_J ; 2 = GND
C25W81  CAP  10.0PF 50V 5% COG  pkg 0402LF  page 252 : 1 = V_IO_HSYNC_J ; 2 = GND
C25W82  CAP  10.0PF 50V 5% COG  pkg 0402LF  page 252 : 1 = V_IO_VSYNC_J ; 2 = GND
C25W90  CAP_A  0.1UF 16V 10% X7R  pkg 0402V  page 252 : 1 = P5V_VGA_D ; 2 = GND
C25W91  CAP_A  1.0UF 6.3V 10% X6S  pkg 0402V  page 254 : 1 = P3V3_STBY ; 2 = GND
C25W92  CAP  1.0UF 16V 10% X6S  pkg 0402  page 255 : 1 = P3V3_STBY ; 2 = GND
C25W93  CAP_A  0.1UF 16V 10% X7R  pkg 0402V  page 255 : 1 = P0V7_GTL2014_VREF_6 ; 2 = GND
C25W94  CAP  1.0UF 16V 10% X6S  pkg 0402  page 254 : 1 = P3V3_STBY ; 2 = GND
C25W95  CAP_A  0.1UF 16V 10% X7R  pkg 0402V  page 254 : 1 = P3V3_STBY ; 2 = GND
C25W96  CAP_A  0.1UF 16V 10% X7R  pkg 0402V  page 255 : 1 = P3V3_STBY ; 2 = GND
C25W97  CAP_A  0.1UF 16V 10% X7R  pkg 0402V  page 255 : 1 = P3V3_STBY ; 2 = GND
C25W98  CAP  1.0UF 16V 10% X6S  pkg 0402  page 255 : 1 = P3V3_STBY ; 2 = GND
C25W99  CAP_A  0.1UF 16V 10% X7R  pkg 0402V  page 254 : 1 = P3V3_STBY ; 2 = GND
C25W100  CAP_A  0.1UF 16V 10% X7R  pkg 0402V  page 255 : 1 = P3V3_STBY ; 2 = GND
C25W101  CAP_A  0.1UF 16V 10% X7R  pkg 0402V  page 254 : 1 = P3V3_STBY ; 2 = GND
C30W1  CAP_A  0.1UF 16V 10% X7R  pkg 0402V  page 253 : 1 = USB3_P01_TXN ; 2 = USB3_P01_C_TXN
C30W2  CAP_A  0.1UF 16V 10% X7R  pkg 0402V  page 253 : 1 = USB3_P01_TXP ; 2 = USB3_P01_C_TXP
C30W3  SC22U16V5MX-4-GP  20%  pkg SMD-BCG5  page 253 : 1 = P5V_STBY_USBC ; 2 = GND
C30W4  SC22U16V5MX-4-GP  20%  pkg SMD-BCG5  page 253 : 1 = P5V_STBY_USBC ; 2 = GND
C30W5  SC22U16V5MX-4-GP  20%  pkg SMD-BCG5  page 253 : 1 = P5V_STBY_USBC ; 2 = GND
C30W6  SC22U16V5MX-4-GP  20%  pkg SMD-BCG5  page 253 : 1 = P5V_STBY_USBC ; 2 = GND
C30W7  SC22U16V5MX-4-GP  20%  pkg SMD-BCG5  page 253 : 1 = P5V_STBY_USBC ; 2 = GND
C30W8  SC22U16V5MX-4-GP  20%  pkg SMD-BCG5  page 253 : 1 = P5V_STBY_USBC ; 2 = GND
C30W9  SC22U16V5MX-4-GP  20%  pkg SMD-BCG5  page 253 : 1 = P5V_STBY_USBC ; 2 = GND
C32W1  CAP_A  0.1UF 16V 10% X7R  pkg 0402V  page 185 : 1 = P1V8_M2 ; 2 = GND
C32W2  CAP_A  0.1UF 16V 10% X7R  pkg 0402V  page 185 : 1 = P3V3_STBY ; 2 = GND
C32W3  CAP_A  0.1UF 16V 10% X7R  pkg 0402V  page 185 : 1 = P1V8_M2 ; 2 = GND
C32W4  CAP_A  0.1UF 16V 10% X7R  pkg 0402V  page 185 : 1 = P3V3_STBY ; 2 = GND
C32W5  CAP  1.0UF 16V 10% X6S  pkg 0402  page 185 : 1 = P1V8_M2 ; 2 = GND
C826  CAP  0.22UF 16V 10% X7R  pkg 0402  page 244 : 1 = P3E_CPU0_PE1_PCH_TXN<14> ; 2 = P3E_CPU0_PE1_PCH_CON_TXN<14>
C827  CAP  0.22UF 16V 10% X7R  pkg 0402  page 244 : 1 = P3E_CPU0_PE1_PCH_TXP<14> ; 2 = P3E_CPU0_PE1_PCH_CON_TXP<14>
C828  CAP  0.22UF 16V 10% X7R  pkg 0402  page 244 : 1 = P3E_CPU0_PE1_PCH_TXN<13> ; 2 = P3E_CPU0_PE1_PCH_CON_TXN<13>
C829  CAP  0.22UF 16V 10% X7R  pkg 0402  page 244 : 1 = P3E_CPU0_PE1_PCH_TXP<13> ; 2 = P3E_CPU0_PE1_PCH_CON_TXP<13>
C830  CAP  0.22UF 16V 10% X7R  pkg 0402  page 244 : 1 = P3E_CPU0_PE1_PCH_TXN<15> ; 2 = P3E_CPU0_PE1_PCH_CON_TXN<15>
C831  CAP  0.22UF 16V 10% X7R  pkg 0402  page 244 : 1 = P3E_CPU0_PE1_PCH_TXP<15> ; 2 = P3E_CPU0_PE1_PCH_CON_TXP<15>
C832  CAP  0.22UF 16V 10% X7R  pkg 0402  page 244 : 1 = P3E_CPU0_PE1_PCH_TXN<11> ; 2 = P3E_CPU0_PE1_PCH_CON_TXN<11>
C833  CAP  0.22UF 16V 10% X7R  pkg 0402  page 244 : 1 = P3E_CPU0_PE1_PCH_TXP<11> ; 2 = P3E_CPU0_PE1_PCH_CON_TXP<11>
C834  CAP  0.22UF 16V 10% X7R  pkg 0402  page 244 : 1 = P3E_CPU0_PE1_PCH_TXN<10> ; 2 = P3E_CPU0_PE1_PCH_CON_TXN<10>
C835  CAP  0.22UF 16V 10% X7R  pkg 0402  page 244 : 1 = P3E_CPU0_PE1_PCH_TXP<10> ; 2 = P3E_CPU0_PE1_PCH_CON_TXP<10>
C840  CAP  0.22UF 16V 10% X7R  pkg 0402  page 244 : 1 = P3E_CPU0_PE1_PCH_TXN<12> ; 2 = P3E_CPU0_PE1_PCH_CON_TXN<12>
C841  CAP  0.22UF 16V 10% X7R  pkg 0402  page 244 : 1 = P3E_CPU0_PE1_PCH_TXP<12> ; 2 = P3E_CPU0_PE1_PCH_CON_TXP<12>
C842  CAP  0.22UF 16V 10% X7R  pkg 0402  page 244 : 1 = P3E_CPU0_PE1_PCH_TXN<8> ; 2 = P3E_CPU0_PE1_PCH_CON_TXN<8>
C843  CAP  0.22UF 16V 10% X7R  pkg 0402  page 244 : 1 = P3E_CPU0_PE1_PCH_TXP<8> ; 2 = P3E_CPU0_PE1_PCH_CON_TXP<8>
C844  CAP  0.22UF 16V 10% X7R  pkg 0402  page 244 : 1 = P3E_CPU0_PE1_PCH_TXN<9> ; 2 = P3E_CPU0_PE1_PCH_CON_TXN<9>
C845  CAP  0.22UF 16V 10% X7R  pkg 0402  page 244 : 1 = P3E_CPU0_PE1_PCH_TXP<9> ; 2 = P3E_CPU0_PE1_PCH_CON_TXP<9>
CF1  SC22P50V2JN-4GP  5%  pkg SMD-BCG  page 201 : 1 = VR_PVCCIN_CPU0_AIREF1 ; 2 = ISENSE_PVCCIN_CPU0_PH1_IMON
CF2  SC22P50V2JN-4GP  5%  pkg SMD-BCG  page 201 : 1 = VR_PVCCIN_CPU0_AIREF2 ; 2 = ISENSE_PVCCIN_CPU0_PH2_IMON
CF3  SC22P50V2JN-4GP  5%  pkg SMD-BCG  page 201 : 1 = VR_PVCCIN_CPU0_AIREF3 ; 2 = ISENSE_PVCCIN_CPU0_PH3_IMON
CF4  SC22P50V2JN-4GP  5%  pkg SMD-BCG  page 201 : 1 = VR_PVCCIN_CPU0_AIREF4 ; 2 = ISENSE_PVCCIN_CPU0_PH4_IMON
CF5  SC22P50V2JN-4GP  5%  pkg SMD-BCG  page 201 : 1 = VR_PVCCIN_CPU0_AIREF5 ; 2 = ISENSE_PVCCIN_CPU0_PH5_IMON
CF6  SC22P50V2JN-4GP  5%  pkg SMD-BCG  page 201 : 1 = VR_PVSA_CPU0_BIREF1 ; 2 = ISENSE_PVSA_CPU0_IMON
CF7  SC22P50V2JN-4GP  5%  pkg SMD-BCG  page 206 : 1 = VR_PVCCIN_CPU1_AIREF1 ; 2 = ISENSE_PVCCIN_CPU1_PH1_IMON
CF8  SC22P50V2JN-4GP  5%  pkg SMD-BCG  page 206 : 1 = VR_PVCCIN_CPU1_AIREF2 ; 2 = ISENSE_PVCCIN_CPU1_PH2_IMON
CF9  SC22P50V2JN-4GP  5%  pkg SMD-BCG  page 206 : 1 = VR_PVCCIN_CPU1_AIREF3 ; 2 = ISENSE_PVCCIN_CPU1_PH3_IMON
CF10  SC22P50V2JN-4GP  5%  pkg SMD-BCG  page 206 : 1 = VR_PVCCIN_CPU1_AIREF4 ; 2 = ISENSE_PVCCIN_CPU1_PH4_IMON
CF11  SC22P50V2JN-4GP  5%  pkg SMD-BCG  page 206 : 1 = VR_PVCCIN_CPU1_AIREF5 ; 2 = ISENSE_PVCCIN_CPU1_PH5_IMON
CF12  SC22P50V2JN-4GP  5%  pkg SMD-BCG  page 206 : 1 = VR_PVSA_CPU1_BIREF1 ; 2 = ISENSE_PVSA_CPU1_IMON
CF13  SC22P50V2JN-4GP  5%  pkg SMD-BCG  page 211 : 1 = VR_PVCCIO_CPU0_AIREF1 ; 2 = ISENSE_PVCCIO_CPU0_PH1_IMON
CF14  SC22P50V2JN-4GP  5%  pkg SMD-BCG  page 213 : 1 = VR_PVCCIO_CPU1_AIREF1 ; 2 = ISENSE_PVCCIO_CPU1_PH1_IMON
CF15  SC22P50V2JN-4GP  5%  pkg SMD-BCG  page 215 : 1 = VR_PVDDQ_ABC_AIREF1 ; 2 = ISENSE_PVDDQ_ABC_PH1_IMON
CF16  SC22P50V2JN-4GP  5%  pkg SMD-BCG  page 215 : 1 = VR_PVDDQ_ABC_AIREF2 ; 2 = ISENSE_PVDDQ_ABC_PH2_IMON
CF17  SC22P50V2JN-4GP  5%  pkg SMD-BCG  page 218 : 1 = VR_PVDDQ_DEF_AIREF1 ; 2 = ISENSE_PVDDQ_DEF_PH1_IMON
CF18  SC22P50V2JN-4GP  5%  pkg SMD-BCG  page 218 : 1 = VR_PVDDQ_DEF_AIREF2 ; 2 = ISENSE_PVDDQ_DEF_PH2_IMON
CF19  SC22P50V2JN-4GP  5%  pkg SMD-BCG  page 223 : 1 = VR_PVDDQ_GHJ_AIREF1 ; 2 = ISENSE_PVDDQ_GHJ_PH1_IMON
CF20  SC22P50V2JN-4GP  5%  pkg SMD-BCG  page 223 : 1 = VR_PVDDQ_GHJ_AIREF2 ; 2 = ISENSE_PVDDQ_GHJ_PH2_IMON
CF21  SC22P50V2JN-4GP  5%  pkg SMD-BCG  page 226 : 1 = VR_PVDDQ_KLM_AIREF1 ; 2 = ISENSE_PVDDQ_KLM_PH1_IMON
CF22  SC22P50V2JN-4GP  5%  pkg SMD-BCG  page 226 : 1 = VR_PVDDQ_KLM_AIREF2 ; 2 = ISENSE_PVDDQ_KLM_PH2_IMON
CF23  SC22P50V2JN-4GP  5%  pkg SMD-BCG  page 235 : 1 = VR_PVNN_PCH_AIREF1 ; 2 = ISENSE_PVNN_PCH_PH1_IMON
CF24  SC22P50V2JN-4GP  5%  pkg SMD-BCG  page 235 : 1 = VR_P1V05_PCH_BIREF1 ; 2 = ISENSE_P1V05_PCH_STBY_PH1_IMON
CN8F1  CAP_A  1.0UF 6.3V 10% X6S  pkg 0402V  page 246 : 1 = P3V3_STBY ; 2 = GND
CN8F2  CAP_A  0.01UF 25V 10% X7R  pkg 0402V  page 246 : 1 = P3V3_STBY ; 2 = GND
